(kicad_pcb
	(version 20260206)
	(generator "pcbnew")
	(generator_version "10.0")
	(general
		(thickness 1.6)
		(legacy_teardrops no)
	)
	(paper "A4")
	(title_block
		(title "03242023_DA0F0TMBIJ0_F0T_Motherboard_J_brd_V01_OCP.brd")
		(comment 1 "Grand Teton / footprints 4942-4949 of 6105")
	)
	(layers
		(0 "F.Cu" signal "TOP")
		(4 "In1.Cu" signal "GND")
		(6 "In2.Cu" signal "IN1")
		(8 "In3.Cu" signal "GND1")
		(10 "In4.Cu" signal "IN2")
		(12 "In5.Cu" signal "GND2")
		(14 "In6.Cu" signal "IN3")
		(16 "In7.Cu" signal "GND3")
		(18 "In8.Cu" signal "VCC")
		(20 "In9.Cu" signal "VCC1")
		(22 "In10.Cu" signal "GND4")
		(24 "In11.Cu" signal "IN4")
		(26 "In12.Cu" signal "GND5")
		(28 "In13.Cu" signal "IN5")
		(30 "In14.Cu" signal "GND6")
		(32 "In15.Cu" signal "IN6")
		(34 "In16.Cu" signal "GND7")
		(2 "B.Cu" signal "BOTTOM")
		(9 "F.Adhes" user "F.Adhesive")
		(11 "B.Adhes" user "B.Adhesive")
		(13 "F.Paste" user "Package Geometry/Pastemask Top")
		(15 "B.Paste" user "Package Geometry/Pastemask Bottom")
		(5 "F.SilkS" user "Ref Des/Silkscreen Top")
		(7 "B.SilkS" user "Ref Des/Silkscreen Bottom")
		(1 "F.Mask" user "Board Geometry/Soldermask Top")
		(3 "B.Mask" user "Board Geometry/Soldermask Bottom")
		(17 "Dwgs.User" user "User.Drawings")
		(19 "Cmts.User" user "User.Comments")
		(21 "Eco1.User" user "User.Eco1")
		(23 "Eco2.User" user "User.Eco2")
		(25 "Edge.Cuts" user "Board Geometry/Outline")
		(27 "Margin" user)
		(31 "F.CrtYd" user "Package Geometry/Place Bound Top")
		(29 "B.CrtYd" user "Package Geometry/Place Bound Bottom")
		(35 "F.Fab" user "Ref Des/Assembly Top")
		(33 "B.Fab" user "Ref Des/Assembly Bottom")
	)
	(footprint ""
		(layer "B.Cu")
		(at 175.355758 -115.375436 180)
		(property "Reference" "C1926"
			(at 0 0 0)
			(layer "B.SilkS")
			(hide yes)
			(effects
				(font
					(size 1.27 1.27)
				)
				(justify mirror)
			)
		)
		(property "Value" ""
			(at 0 0 0)
			(layer "B.Fab")
			(effects
				(font
					(size 1.27 1.27)
				)
				(justify mirror)
			)
		)
		(duplicate_pad_numbers_are_jumpers no)
		(fp_line
			(start 0.69215 0.2921)
			(end 0.69215 -0.2921)
			(stroke
				(width 0.1524)
				(type default)
			)
			(layer "B.SilkS")
		)
		(fp_line
			(start 0.69215 -0.2921)
			(end -0.69215 -0.2921)
			(stroke
				(width 0.1524)
				(type default)
			)
			(layer "B.SilkS")
		)
		(fp_line
			(start -0.69215 0.2921)
			(end 0.69215 0.2921)
			(stroke
				(width 0.1524)
				(type default)
			)
			(layer "B.SilkS")
		)
		(fp_line
			(start -0.69215 -0.2921)
			(end -0.69215 0.2921)
			(stroke
				(width 0.1524)
				(type default)
			)
			(layer "B.SilkS")
		)
		(fp_line
			(start 0.51435 0.2794)
			(end 0.51435 -0.2794)
			(stroke
				(width 0.1)
				(type default)
			)
			(layer "B.Fab")
		)
		(fp_line
			(start 0.51435 -0.2794)
			(end -0.51435 -0.2794)
			(stroke
				(width 0.1)
				(type default)
			)
			(layer "B.Fab")
		)
		(fp_line
			(start -0.51435 0.2794)
			(end 0.51435 0.2794)
			(stroke
				(width 0.1)
				(type default)
			)
			(layer "B.Fab")
		)
		(fp_line
			(start -0.51435 -0.2794)
			(end -0.51435 0.2794)
			(stroke
				(width 0.1)
				(type default)
			)
			(layer "B.Fab")
		)
		(pad "1" smd circle
			(at 0.40005 0)
			(size 0 0)
			(layers "B.Cu" "B.Mask" "B.Paste")
			(net "P3V3_AUX_FPGA_VCCIO0")
		)
		(pad "2" smd circle
			(at -0.40005 0)
			(size 0 0)
			(layers "B.Cu" "B.Mask" "B.Paste")
			(net "GND")
		)
		(zone
			(layer "B.Cu")
			(hatch none 0.5)
			(connect_pads
				(clearance 0)
			)
			(min_thickness 0.25)
			(keepout
				(tracks not_allowed)
				(vias allowed)
				(pads allowed)
				(copperpour not_allowed)
				(footprints allowed)
			)
			(placement
				(enabled no)
				(sheetname "")
			)
			(fill
				(thermal_gap 0.5)
				(thermal_bridge_width 0.5)
				(island_removal_mode 0)
			)
			(polygon
				(pts
					(xy 175.165258 -115.463066) (xy 175.256698 -115.521232) (xy 175.456088 -115.521232) (xy 175.546258 -115.463066)
					(xy 175.546258 -115.287806) (xy 175.456088 -115.229386) (xy 175.256698 -115.229386) (xy 175.165258 -115.287552)
				)
			)
		)
	)
	(footprint ""
		(layer "B.Cu")
		(at 346.441014 -337.564984 -90)
		(property "Reference" "PC307_P0_1"
			(at 0 0 90)
			(layer "B.SilkS")
			(hide yes)
			(effects
				(font
					(size 1.27 1.27)
				)
				(justify mirror)
			)
		)
		(property "Value" ""
			(at 0 0 90)
			(layer "B.Fab")
			(effects
				(font
					(size 1.27 1.27)
				)
				(justify mirror)
			)
		)
		(duplicate_pad_numbers_are_jumpers no)
		(fp_line
			(start -1.524 0.762)
			(end 1.524 0.762)
			(stroke
				(width 0.1524)
				(type default)
			)
			(layer "B.SilkS")
		)
		(fp_line
			(start 1.524 0.762)
			(end 1.524 -0.762)
			(stroke
				(width 0.1524)
				(type default)
			)
			(layer "B.SilkS")
		)
		(fp_line
			(start -1.524 -0.762)
			(end -1.524 0.762)
			(stroke
				(width 0.1524)
				(type default)
			)
			(layer "B.SilkS")
		)
		(fp_line
			(start 1.524 -0.762)
			(end -1.524 -0.762)
			(stroke
				(width 0.1524)
				(type default)
			)
			(layer "B.SilkS")
		)
		(fp_line
			(start -1.1049 0.724916)
			(end -1.1049 -0.724916)
			(stroke
				(width 0.1)
				(type default)
			)
			(layer "B.Fab")
		)
		(fp_line
			(start 1.1049 0.724916)
			(end -1.1049 0.724916)
			(stroke
				(width 0.1)
				(type default)
			)
			(layer "B.Fab")
		)
		(fp_line
			(start -1.1049 -0.724916)
			(end 1.1049 -0.724916)
			(stroke
				(width 0.1)
				(type default)
			)
			(layer "B.Fab")
		)
		(fp_line
			(start 1.1049 -0.724916)
			(end 1.1049 0.724916)
			(stroke
				(width 0.1)
				(type default)
			)
			(layer "B.Fab")
		)
		(pad "1" smd rect
			(at 0.889 0 270)
			(size 1.016 1.27)
			(layers "B.Cu" "B.Mask" "B.Paste")
			(net "SW_P12V_PVCCIN_CPU0_FLT")
		)
		(pad "2" smd rect
			(at -0.889 0 270)
			(size 1.016 1.27)
			(layers "B.Cu" "B.Mask" "B.Paste")
			(net "GND")
		)
	)
	(footprint ""
		(layer "B.Cu")
		(at 27.304746 -321.554856 -90)
		(property "Reference" "C63"
			(at 0 0 90)
			(layer "B.SilkS")
			(hide yes)
			(effects
				(font
					(size 1.27 1.27)
				)
				(justify mirror)
			)
		)
		(property "Value" ""
			(at 0 0 90)
			(layer "B.Fab")
			(effects
				(font
					(size 1.27 1.27)
				)
				(justify mirror)
			)
		)
		(duplicate_pad_numbers_are_jumpers no)
		(fp_line
			(start -1.524 0.762)
			(end 1.524 0.762)
			(stroke
				(width 0.1524)
				(type default)
			)
			(layer "B.SilkS")
		)
		(fp_line
			(start 1.524 0.762)
			(end 1.524 -0.762)
			(stroke
				(width 0.1524)
				(type default)
			)
			(layer "B.SilkS")
		)
		(fp_line
			(start -1.524 -0.762)
			(end -1.524 0.762)
			(stroke
				(width 0.1524)
				(type default)
			)
			(layer "B.SilkS")
		)
		(fp_line
			(start 1.524 -0.762)
			(end -1.524 -0.762)
			(stroke
				(width 0.1524)
				(type default)
			)
			(layer "B.SilkS")
		)
		(fp_line
			(start -1.1049 0.724916)
			(end -1.1049 -0.724916)
			(stroke
				(width 0.1)
				(type default)
			)
			(layer "B.Fab")
		)
		(fp_line
			(start 1.1049 0.724916)
			(end -1.1049 0.724916)
			(stroke
				(width 0.1)
				(type default)
			)
			(layer "B.Fab")
		)
		(fp_line
			(start -1.1049 -0.724916)
			(end 1.1049 -0.724916)
			(stroke
				(width 0.1)
				(type default)
			)
			(layer "B.Fab")
		)
		(fp_line
			(start 1.1049 -0.724916)
			(end 1.1049 0.724916)
			(stroke
				(width 0.1)
				(type default)
			)
			(layer "B.Fab")
		)
		(pad "1" smd rect
			(at 0.889 0 270)
			(size 1.016 1.27)
			(layers "B.Cu" "B.Mask" "B.Paste")
			(net "P12V_S3_AUX_CPU1_NVDIMM")
		)
		(pad "2" smd rect
			(at -0.889 0 270)
			(size 1.016 1.27)
			(layers "B.Cu" "B.Mask" "B.Paste")
			(net "GND")
		)
	)
	(footprint ""
		(layer "B.Cu")
		(at 41.830244 -100.55733 90)
		(property "Reference" "R3940"
			(at 0 0 90)
			(layer "B.SilkS")
			(hide yes)
			(effects
				(font
					(size 1.27 1.27)
				)
				(justify mirror)
			)
		)
		(property "Value" ""
			(at 0 0 90)
			(layer "B.Fab")
			(effects
				(font
					(size 1.27 1.27)
				)
				(justify mirror)
			)
		)
		(duplicate_pad_numbers_are_jumpers no)
		(fp_line
			(start 0.7874 -0.4064)
			(end -0.7874 -0.4064)
			(stroke
				(width 0.1524)
				(type default)
			)
			(layer "B.SilkS")
		)
		(fp_line
			(start -0.7874 -0.4064)
			(end -0.7874 0.4064)
			(stroke
				(width 0.1524)
				(type default)
			)
			(layer "B.SilkS")
		)
		(fp_line
			(start 0.7874 0.4064)
			(end 0.7874 -0.4064)
			(stroke
				(width 0.1524)
				(type default)
			)
			(layer "B.SilkS")
		)
		(fp_line
			(start -0.7874 0.4064)
			(end 0.7874 0.4064)
			(stroke
				(width 0.1524)
				(type default)
			)
			(layer "B.SilkS")
		)
		(fp_line
			(start 0.67945 -0.305054)
			(end 0.12065 -0.305054)
			(stroke
				(width 0.1)
				(type default)
			)
			(layer "B.Fab")
		)
		(fp_line
			(start 0.12065 -0.305054)
			(end 0.12065 -0.2794)
			(stroke
				(width 0.1)
				(type default)
			)
			(layer "B.Fab")
		)
		(fp_line
			(start -0.12065 -0.3048)
			(end -0.67945 -0.3048)
			(stroke
				(width 0.1)
				(type default)
			)
			(layer "B.Fab")
		)
		(fp_line
			(start -0.67945 -0.3048)
			(end -0.67945 0.3048)
			(stroke
				(width 0.1)
				(type default)
			)
			(layer "B.Fab")
		)
		(fp_line
			(start 0.12065 -0.2794)
			(end -0.12065 -0.2794)
			(stroke
				(width 0.1)
				(type default)
			)
			(layer "B.Fab")
		)
		(fp_line
			(start -0.12065 -0.2794)
			(end -0.12065 -0.3048)
			(stroke
				(width 0.1)
				(type default)
			)
			(layer "B.Fab")
		)
		(fp_line
			(start 0.12065 0.2794)
			(end 0.12065 0.3048)
			(stroke
				(width 0.1)
				(type default)
			)
			(layer "B.Fab")
		)
		(fp_line
			(start -0.120396 0.2794)
			(end 0.12065 0.2794)
			(stroke
				(width 0.1)
				(type default)
			)
			(layer "B.Fab")
		)
		(fp_line
			(start 0.67945 0.3048)
			(end 0.67945 -0.305054)
			(stroke
				(width 0.1)
				(type default)
			)
			(layer "B.Fab")
		)
		(fp_line
			(start 0.12065 0.3048)
			(end 0.67945 0.3048)
			(stroke
				(width 0.1)
				(type default)
			)
			(layer "B.Fab")
		)
		(fp_line
			(start -0.120396 0.3048)
			(end -0.120396 0.2794)
			(stroke
				(width 0.1)
				(type default)
			)
			(layer "B.Fab")
		)
		(fp_line
			(start -0.67945 0.3048)
			(end -0.120396 0.3048)
			(stroke
				(width 0.1)
				(type default)
			)
			(layer "B.Fab")
		)
		(pad "1" smd rect
			(at 0.40005 0 90)
			(size 0.4572 0.508)
			(layers "B.Cu" "B.Mask" "B.Paste")
			(net "P12V_E1S_0_ISENSE_MPS_MAM")
		)
		(pad "2" smd rect
			(at -0.40005 0 90)
			(size 0.4572 0.508)
			(layers "B.Cu" "B.Mask" "B.Paste")
			(net "P12V_E1S_0_ISENSE_MAM")
		)
	)
	(footprint ""
		(layer "B.Cu")
		(at 108.42117 -418.336222 180)
		(property "Reference" "R4475"
			(at 0 0 0)
			(layer "B.SilkS")
			(hide yes)
			(effects
				(font
					(size 1.27 1.27)
				)
				(justify mirror)
			)
		)
		(property "Value" ""
			(at 0 0 0)
			(layer "B.Fab")
			(effects
				(font
					(size 1.27 1.27)
				)
				(justify mirror)
			)
		)
		(duplicate_pad_numbers_are_jumpers no)
		(fp_line
			(start 1.2954 0.5842)
			(end 1.2954 -0.5842)
			(stroke
				(width 0.1524)
				(type default)
			)
			(layer "B.SilkS")
		)
		(fp_line
			(start 1.2954 -0.5842)
			(end -1.2954 -0.5842)
			(stroke
				(width 0.1524)
				(type default)
			)
			(layer "B.SilkS")
		)
		(fp_line
			(start -1.2954 0.5842)
			(end 1.2954 0.5842)
			(stroke
				(width 0.1524)
				(type default)
			)
			(layer "B.SilkS")
		)
		(fp_line
			(start -1.2954 -0.5842)
			(end -1.2954 0.5842)
			(stroke
				(width 0.1524)
				(type default)
			)
			(layer "B.SilkS")
		)
		(fp_line
			(start 1.1938 0.4064)
			(end 1.1938 -0.406654)
			(stroke
				(width 0.1)
				(type default)
			)
			(layer "B.Fab")
		)
		(fp_line
			(start 1.1938 -0.406654)
			(end 0.8636 -0.406654)
			(stroke
				(width 0.1)
				(type default)
			)
			(layer "B.Fab")
		)
		(fp_line
			(start 0.8636 0.4572)
			(end 0.8636 0.4318)
			(stroke
				(width 0.1)
				(type default)
			)
			(layer "B.Fab")
		)
		(fp_line
			(start 0.8636 0.4318)
			(end 0.8636 0.4064)
			(stroke
				(width 0.1)
				(type default)
			)
			(layer "B.Fab")
		)
		(fp_line
			(start 0.8636 0.4064)
			(end 1.1938 0.4064)
			(stroke
				(width 0.1)
				(type default)
			)
			(layer "B.Fab")
		)
		(fp_line
			(start 0.8636 -0.406654)
			(end 0.8636 -0.4572)
			(stroke
				(width 0.1)
				(type default)
			)
			(layer "B.Fab")
		)
		(fp_line
			(start 0.8636 -0.4572)
			(end -0.8636 -0.4572)
			(stroke
				(width 0.1)
				(type default)
			)
			(layer "B.Fab")
		)
		(fp_line
			(start -0.8636 0.4572)
			(end 0.8636 0.4572)
			(stroke
				(width 0.1)
				(type default)
			)
			(layer "B.Fab")
		)
		(fp_line
			(start -0.8636 0.4064)
			(end -0.8636 0.4572)
			(stroke
				(width 0.1)
				(type default)
			)
			(layer "B.Fab")
		)
		(fp_line
			(start -0.8636 -0.406654)
			(end -1.1938 -0.406654)
			(stroke
				(width 0.1)
				(type default)
			)
			(layer "B.Fab")
		)
		(fp_line
			(start -0.8636 -0.4572)
			(end -0.8636 -0.406654)
			(stroke
				(width 0.1)
				(type default)
			)
			(layer "B.Fab")
		)
		(fp_line
			(start -1.1938 0.4064)
			(end -0.8636 0.4064)
			(stroke
				(width 0.1)
				(type default)
			)
			(layer "B.Fab")
		)
		(fp_line
			(start -1.1938 -0.406654)
			(end -1.1938 0.4064)
			(stroke
				(width 0.1)
				(type default)
			)
			(layer "B.Fab")
		)
		(pad "1" smd rect
			(at 0.7366 0 90)
			(size 0.7112 0.8128)
			(layers "B.Cu" "B.Mask" "B.Paste")
			(net "P3V3_9ZXL045")
		)
		(pad "2" smd rect
			(at -0.7366 0 90)
			(size 0.7112 0.8128)
			(layers "B.Cu" "B.Mask" "B.Paste")
			(net "P3V3_9ZXL045_VDDR")
		)
	)
	(footprint ""
		(layer "B.Cu")
		(at 341.125048 -52.080922 -90)
		(property "Reference" "C1265"
			(at 0 0 90)
			(layer "B.SilkS")
			(hide yes)
			(effects
				(font
					(size 1.27 1.27)
				)
				(justify mirror)
			)
		)
		(property "Value" ""
			(at 0 0 90)
			(layer "B.Fab")
			(effects
				(font
					(size 1.27 1.27)
				)
				(justify mirror)
			)
		)
		(duplicate_pad_numbers_are_jumpers no)
		(fp_line
			(start -0.7874 0.4064)
			(end 0.7874 0.4064)
			(stroke
				(width 0.1524)
				(type default)
			)
			(layer "B.SilkS")
		)
		(fp_line
			(start 0.7874 0.4064)
			(end 0.7874 -0.4064)
			(stroke
				(width 0.1524)
				(type default)
			)
			(layer "B.SilkS")
		)
		(fp_line
			(start -0.7874 -0.4064)
			(end -0.7874 0.4064)
			(stroke
				(width 0.1524)
				(type default)
			)
			(layer "B.SilkS")
		)
		(fp_line
			(start 0.7874 -0.4064)
			(end -0.7874 -0.4064)
			(stroke
				(width 0.1524)
				(type default)
			)
			(layer "B.SilkS")
		)
		(fp_line
			(start -0.67945 0.3048)
			(end -0.120396 0.3048)
			(stroke
				(width 0.1)
				(type default)
			)
			(layer "B.Fab")
		)
		(fp_line
			(start -0.120396 0.3048)
			(end -0.120396 0.2794)
			(stroke
				(width 0.1)
				(type default)
			)
			(layer "B.Fab")
		)
		(fp_line
			(start 0.12065 0.3048)
			(end 0.67945 0.3048)
			(stroke
				(width 0.1)
				(type default)
			)
			(layer "B.Fab")
		)
		(fp_line
			(start 0.67945 0.3048)
			(end 0.67945 -0.305054)
			(stroke
				(width 0.1)
				(type default)
			)
			(layer "B.Fab")
		)
		(fp_line
			(start -0.120396 0.2794)
			(end 0.12065 0.2794)
			(stroke
				(width 0.1)
				(type default)
			)
			(layer "B.Fab")
		)
		(fp_line
			(start 0.12065 0.2794)
			(end 0.12065 0.3048)
			(stroke
				(width 0.1)
				(type default)
			)
			(layer "B.Fab")
		)
		(fp_line
			(start -0.12065 -0.2794)
			(end -0.12065 -0.3048)
			(stroke
				(width 0.1)
				(type default)
			)
			(layer "B.Fab")
		)
		(fp_line
			(start 0.12065 -0.2794)
			(end -0.12065 -0.2794)
			(stroke
				(width 0.1)
				(type default)
			)
			(layer "B.Fab")
		)
		(fp_line
			(start -0.67945 -0.3048)
			(end -0.67945 0.3048)
			(stroke
				(width 0.1)
				(type default)
			)
			(layer "B.Fab")
		)
		(fp_line
			(start -0.12065 -0.3048)
			(end -0.67945 -0.3048)
			(stroke
				(width 0.1)
				(type default)
			)
			(layer "B.Fab")
		)
		(fp_line
			(start 0.12065 -0.305054)
			(end 0.12065 -0.2794)
			(stroke
				(width 0.1)
				(type default)
			)
			(layer "B.Fab")
		)
		(fp_line
			(start 0.67945 -0.305054)
			(end 0.12065 -0.305054)
			(stroke
				(width 0.1)
				(type default)
			)
			(layer "B.Fab")
		)
		(pad "1" smd circle
			(at 0.40005 0 90)
			(size 0 0)
			(layers "B.Cu" "B.Mask" "B.Paste")
			(net "P1V8_PCH_PLL_AUX")
		)
		(pad "2" smd circle
			(at -0.40005 0 90)
			(size 0 0)
			(layers "B.Cu" "B.Mask" "B.Paste")
			(net "GND")
		)
	)
	(footprint ""
		(layer "B.Cu")
		(at 15.696946 -321.554856 -90)
		(property "Reference" "C98"
			(at 0 0 90)
			(layer "B.SilkS")
			(hide yes)
			(effects
				(font
					(size 1.27 1.27)
				)
				(justify mirror)
			)
		)
		(property "Value" ""
			(at 0 0 90)
			(layer "B.Fab")
			(effects
				(font
					(size 1.27 1.27)
				)
				(justify mirror)
			)
		)
		(duplicate_pad_numbers_are_jumpers no)
		(fp_line
			(start -1.524 0.762)
			(end 1.524 0.762)
			(stroke
				(width 0.1524)
				(type default)
			)
			(layer "B.SilkS")
		)
		(fp_line
			(start 1.524 0.762)
			(end 1.524 -0.762)
			(stroke
				(width 0.1524)
				(type default)
			)
			(layer "B.SilkS")
		)
		(fp_line
			(start -1.524 -0.762)
			(end -1.524 0.762)
			(stroke
				(width 0.1524)
				(type default)
			)
			(layer "B.SilkS")
		)
		(fp_line
			(start 1.524 -0.762)
			(end -1.524 -0.762)
			(stroke
				(width 0.1524)
				(type default)
			)
			(layer "B.SilkS")
		)
		(fp_line
			(start -1.1049 0.724916)
			(end -1.1049 -0.724916)
			(stroke
				(width 0.1)
				(type default)
			)
			(layer "B.Fab")
		)
		(fp_line
			(start 1.1049 0.724916)
			(end -1.1049 0.724916)
			(stroke
				(width 0.1)
				(type default)
			)
			(layer "B.Fab")
		)
		(fp_line
			(start -1.1049 -0.724916)
			(end 1.1049 -0.724916)
			(stroke
				(width 0.1)
				(type default)
			)
			(layer "B.Fab")
		)
		(fp_line
			(start 1.1049 -0.724916)
			(end 1.1049 0.724916)
			(stroke
				(width 0.1)
				(type default)
			)
			(layer "B.Fab")
		)
		(pad "1" smd rect
			(at 0.889 0 270)
			(size 1.016 1.27)
			(layers "B.Cu" "B.Mask" "B.Paste")
			(net "P12V_S3_AUX_CPU1_NVDIMM")
		)
		(pad "2" smd rect
			(at -0.889 0 270)
			(size 1.016 1.27)
			(layers "B.Cu" "B.Mask" "B.Paste")
			(net "GND")
		)
	)
	(footprint ""
		(layer "B.Cu")
		(at 451.962012 -58.325512 -90)
		(property "Reference" "PC1868"
			(at 0 0 90)
			(layer "B.SilkS")
			(hide yes)
			(effects
				(font
					(size 1.27 1.27)
				)
				(justify mirror)
			)
		)
		(property "Value" ""
			(at 0 0 90)
			(layer "B.Fab")
			(effects
				(font
					(size 1.27 1.27)
				)
				(justify mirror)
			)
		)
		(duplicate_pad_numbers_are_jumpers no)
		(fp_line
			(start -1.524 0.762)
			(end 1.524 0.762)
			(stroke
				(width 0.1524)
				(type default)
			)
			(layer "B.SilkS")
		)
		(fp_line
			(start 1.524 0.762)
			(end 1.524 -0.762)
			(stroke
				(width 0.1524)
				(type default)
			)
			(layer "B.SilkS")
		)
		(fp_line
			(start -1.524 -0.762)
			(end -1.524 0.762)
			(stroke
				(width 0.1524)
				(type default)
			)
			(layer "B.SilkS")
		)
		(fp_line
			(start 1.524 -0.762)
			(end -1.524 -0.762)
			(stroke
				(width 0.1524)
				(type default)
			)
			(layer "B.SilkS")
		)
		(fp_line
			(start -1.1049 0.724916)
			(end -1.1049 -0.724916)
			(stroke
				(width 0.1)
				(type default)
			)
			(layer "B.Fab")
		)
		(fp_line
			(start 1.1049 0.724916)
			(end -1.1049 0.724916)
			(stroke
				(width 0.1)
				(type default)
			)
			(layer "B.Fab")
		)
		(fp_line
			(start -1.1049 -0.724916)
			(end 1.1049 -0.724916)
			(stroke
				(width 0.1)
				(type default)
			)
			(layer "B.Fab")
		)
		(fp_line
			(start 1.1049 -0.724916)
			(end 1.1049 0.724916)
			(stroke
				(width 0.1)
				(type default)
			)
			(layer "B.Fab")
		)
		(pad "1" smd rect
			(at 0.889 0 270)
			(size 1.016 1.27)
			(layers "B.Cu" "B.Mask" "B.Paste")
			(net "P3V3_AUX")
		)
		(pad "2" smd rect
			(at -0.889 0 270)
			(size 1.016 1.27)
			(layers "B.Cu" "B.Mask" "B.Paste")
			(net "GND")
		)
	)
)
